FILE_TYPE=LIBRARY_PARTS;
primitive 'SCONN120_H61426002','SCONN120_H61426002_SM';
  pin
    'IOA1':
      PIN_NUMBER='(A1)';
      BIDIRECTIONAL='TRUE';
      INPUT_LOAD='(-0.01,0.01)';
      OUTPUT_LOAD='(1.0,-1.0)';
    'IOA10':
      PIN_NUMBER='(A10)';
      BIDIRECTIONAL='TRUE';
      INPUT_LOAD='(-0.01,0.01)';
      OUTPUT_LOAD='(1.0,-1.0)';
    'IOA11':
      PIN_NUMBER='(A11)';
      BIDIRECTIONAL='TRUE';
      INPUT_LOAD='(-0.01,0.01)';
      OUTPUT_LOAD='(1.0,-1.0)';
    'IOA12':
      PIN_NUMBER='(A12)';
      BIDIRECTIONAL='TRUE';
      INPUT_LOAD='(-0.01,0.01)';
      OUTPUT_LOAD='(1.0,-1.0)';
    'IOA13':
      PIN_NUMBER='(A13)';
      BIDIRECTIONAL='TRUE';
      INPUT_LOAD='(-0.01,0.01)';
      OUTPUT_LOAD='(1.0,-1.0)';
    'IOA14':
      PIN_NUMBER='(A14)';
      BIDIRECTIONAL='TRUE';
      INPUT_LOAD='(-0.01,0.01)';
      OUTPUT_LOAD='(1.0,-1.0)';
    'IOA15':
      PIN_NUMBER='(A15)';
      BIDIRECTIONAL='TRUE';
      INPUT_LOAD='(-0.01,0.01)';
      OUTPUT_LOAD='(1.0,-1.0)';
    'IOA16':
      PIN_NUMBER='(A16)';
      BIDIRECTIONAL='TRUE';
      INPUT_LOAD='(-0.01,0.01)';
      OUTPUT_LOAD='(1.0,-1.0)';
    'IOA17':
      PIN_NUMBER='(A17)';
      BIDIRECTIONAL='TRUE';
      INPUT_LOAD='(-0.01,0.01)';
      OUTPUT_LOAD='(1.0,-1.0)';
    'IOA18':
      PIN_NUMBER='(A18)';
      BIDIRECTIONAL='TRUE';
      INPUT_LOAD='(-0.01,0.01)';
      OUTPUT_LOAD='(1.0,-1.0)';
    'IOA19':
      PIN_NUMBER='(A19)';
      BIDIRECTIONAL='TRUE';
      INPUT_LOAD='(-0.01,0.01)';
      OUTPUT_LOAD='(1.0,-1.0)';
    'IOA2':
      PIN_NUMBER='(A2)';
      BIDIRECTIONAL='TRUE';
      INPUT_LOAD='(-0.01,0.01)';
      OUTPUT_LOAD='(1.0,-1.0)';
    'IOA20':
      PIN_NUMBER='(A20)';
      BIDIRECTIONAL='TRUE';
      INPUT_LOAD='(-0.01,0.01)';
      OUTPUT_LOAD='(1.0,-1.0)';
    'IOA3':
      PIN_NUMBER='(A3)';
      BIDIRECTIONAL='TRUE';
      INPUT_LOAD='(-0.01,0.01)';
      OUTPUT_LOAD='(1.0,-1.0)';
    'IOA4':
      PIN_NUMBER='(A4)';
      BIDIRECTIONAL='TRUE';
      INPUT_LOAD='(-0.01,0.01)';
      OUTPUT_LOAD='(1.0,-1.0)';
    'IOA5':
      PIN_NUMBER='(A5)';
      BIDIRECTIONAL='TRUE';
      INPUT_LOAD='(-0.01,0.01)';
      OUTPUT_LOAD='(1.0,-1.0)';
    'IOA6':
      PIN_NUMBER='(A6)';
      BIDIRECTIONAL='TRUE';
      INPUT_LOAD='(-0.01,0.01)';
      OUTPUT_LOAD='(1.0,-1.0)';
    'IOA7':
      PIN_NUMBER='(A7)';
      BIDIRECTIONAL='TRUE';
      INPUT_LOAD='(-0.01,0.01)';
      OUTPUT_LOAD='(1.0,-1.0)';
    'IOA8':
      PIN_NUMBER='(A8)';
      BIDIRECTIONAL='TRUE';
      INPUT_LOAD='(-0.01,0.01)';
      OUTPUT_LOAD='(1.0,-1.0)';
    'IOA9':
      PIN_NUMBER='(A9)';
      BIDIRECTIONAL='TRUE';
      INPUT_LOAD='(-0.01,0.01)';
      OUTPUT_LOAD='(1.0,-1.0)';
    'IOB1':
      PIN_NUMBER='(B1)';
      BIDIRECTIONAL='TRUE';
      INPUT_LOAD='(-0.01,0.01)';
      OUTPUT_LOAD='(1.0,-1.0)';
    'IOB10':
      PIN_NUMBER='(B10)';
      BIDIRECTIONAL='TRUE';
      INPUT_LOAD='(-0.01,0.01)';
      OUTPUT_LOAD='(1.0,-1.0)';
    'IOB11':
      PIN_NUMBER='(B11)';
      BIDIRECTIONAL='TRUE';
      INPUT_LOAD='(-0.01,0.01)';
      OUTPUT_LOAD='(1.0,-1.0)';
    'IOB12':
      PIN_NUMBER='(B12)';
      BIDIRECTIONAL='TRUE';
      INPUT_LOAD='(-0.01,0.01)';
      OUTPUT_LOAD='(1.0,-1.0)';
    'IOB13':
      PIN_NUMBER='(B13)';
      BIDIRECTIONAL='TRUE';
      INPUT_LOAD='(-0.01,0.01)';
      OUTPUT_LOAD='(1.0,-1.0)';
    'IOB14':
      PIN_NUMBER='(B14)';
      BIDIRECTIONAL='TRUE';
      INPUT_LOAD='(-0.01,0.01)';
      OUTPUT_LOAD='(1.0,-1.0)';
    'IOB15':
      PIN_NUMBER='(B15)';
      BIDIRECTIONAL='TRUE';
      INPUT_LOAD='(-0.01,0.01)';
      OUTPUT_LOAD='(1.0,-1.0)';
    'IOB16':
      PIN_NUMBER='(B16)';
      BIDIRECTIONAL='TRUE';
      INPUT_LOAD='(-0.01,0.01)';
      OUTPUT_LOAD='(1.0,-1.0)';
    'IOB17':
      PIN_NUMBER='(B17)';
      BIDIRECTIONAL='TRUE';
      INPUT_LOAD='(-0.01,0.01)';
      OUTPUT_LOAD='(1.0,-1.0)';
    'IOB18':
      PIN_NUMBER='(B18)';
      BIDIRECTIONAL='TRUE';
      INPUT_LOAD='(-0.01,0.01)';
      OUTPUT_LOAD='(1.0,-1.0)';
    'IOB19':
      PIN_NUMBER='(B19)';
      BIDIRECTIONAL='TRUE';
      INPUT_LOAD='(-0.01,0.01)';
      OUTPUT_LOAD='(1.0,-1.0)';
    'IOB2':
      PIN_NUMBER='(B2)';
      BIDIRECTIONAL='TRUE';
      INPUT_LOAD='(-0.01,0.01)';
      OUTPUT_LOAD='(1.0,-1.0)';
    'IOB20':
      PIN_NUMBER='(B20)';
      BIDIRECTIONAL='TRUE';
      INPUT_LOAD='(-0.01,0.01)';
      OUTPUT_LOAD='(1.0,-1.0)';
    'IOB3':
      PIN_NUMBER='(B3)';
      BIDIRECTIONAL='TRUE';
      INPUT_LOAD='(-0.01,0.01)';
      OUTPUT_LOAD='(1.0,-1.0)';
    'IOB4':
      PIN_NUMBER='(B4)';
      BIDIRECTIONAL='TRUE';
      INPUT_LOAD='(-0.01,0.01)';
      OUTPUT_LOAD='(1.0,-1.0)';
    'IOB5':
      PIN_NUMBER='(B5)';
      BIDIRECTIONAL='TRUE';
      INPUT_LOAD='(-0.01,0.01)';
      OUTPUT_LOAD='(1.0,-1.0)';
    'IOB6':
      PIN_NUMBER='(B6)';
      BIDIRECTIONAL='TRUE';
      INPUT_LOAD='(-0.01,0.01)';
      OUTPUT_LOAD='(1.0,-1.0)';
    'IOB7':
      PIN_NUMBER='(B7)';
      BIDIRECTIONAL='TRUE';
      INPUT_LOAD='(-0.01,0.01)';
      OUTPUT_LOAD='(1.0,-1.0)';
    'IOB8':
      PIN_NUMBER='(B8)';
      BIDIRECTIONAL='TRUE';
      INPUT_LOAD='(-0.01,0.01)';
      OUTPUT_LOAD='(1.0,-1.0)';
    'IOB9':
      PIN_NUMBER='(B9)';
      BIDIRECTIONAL='TRUE';
      INPUT_LOAD='(-0.01,0.01)';
      OUTPUT_LOAD='(1.0,-1.0)';
    'IOC1':
      PIN_NUMBER='(C1)';
      BIDIRECTIONAL='TRUE';
      INPUT_LOAD='(-0.01,0.01)';
      OUTPUT_LOAD='(1.0,-1.0)';
    'IOC10':
      PIN_NUMBER='(C10)';
      BIDIRECTIONAL='TRUE';
      INPUT_LOAD='(-0.01,0.01)';
      OUTPUT_LOAD='(1.0,-1.0)';
    'IOC11':
      PIN_NUMBER='(C11)';
      BIDIRECTIONAL='TRUE';
      INPUT_LOAD='(-0.01,0.01)';
      OUTPUT_LOAD='(1.0,-1.0)';
    'IOC12':
      PIN_NUMBER='(C12)';
      BIDIRECTIONAL='TRUE';
      INPUT_LOAD='(-0.01,0.01)';
      OUTPUT_LOAD='(1.0,-1.0)';
    'IOC13':
      PIN_NUMBER='(C13)';
      BIDIRECTIONAL='TRUE';
      INPUT_LOAD='(-0.01,0.01)';
      OUTPUT_LOAD='(1.0,-1.0)';
    'IOC14':
      PIN_NUMBER='(C14)';
      BIDIRECTIONAL='TRUE';
      INPUT_LOAD='(-0.01,0.01)';
      OUTPUT_LOAD='(1.0,-1.0)';
    'IOC15':
      PIN_NUMBER='(C15)';
      BIDIRECTIONAL='TRUE';
      INPUT_LOAD='(-0.01,0.01)';
      OUTPUT_LOAD='(1.0,-1.0)';
    'IOC16':
      PIN_NUMBER='(C16)';
      BIDIRECTIONAL='TRUE';
      INPUT_LOAD='(-0.01,0.01)';
      OUTPUT_LOAD='(1.0,-1.0)';
    'IOC17':
      PIN_NUMBER='(C17)';
      BIDIRECTIONAL='TRUE';
      INPUT_LOAD='(-0.01,0.01)';
      OUTPUT_LOAD='(1.0,-1.0)';
    'IOC18':
      PIN_NUMBER='(C18)';
      BIDIRECTIONAL='TRUE';
      INPUT_LOAD='(-0.01,0.01)';
      OUTPUT_LOAD='(1.0,-1.0)';
    'IOC19':
      PIN_NUMBER='(C19)';
      BIDIRECTIONAL='TRUE';
      INPUT_LOAD='(-0.01,0.01)';
      OUTPUT_LOAD='(1.0,-1.0)';
    'IOC2':
      PIN_NUMBER='(C2)';
      BIDIRECTIONAL='TRUE';
      INPUT_LOAD='(-0.01,0.01)';
      OUTPUT_LOAD='(1.0,-1.0)';
    'IOC20':
      PIN_NUMBER='(C20)';
      BIDIRECTIONAL='TRUE';
      INPUT_LOAD='(-0.01,0.01)';
      OUTPUT_LOAD='(1.0,-1.0)';
    'IOC3':
      PIN_NUMBER='(C3)';
      BIDIRECTIONAL='TRUE';
      INPUT_LOAD='(-0.01,0.01)';
      OUTPUT_LOAD='(1.0,-1.0)';
    'IOC4':
      PIN_NUMBER='(C4)';
      BIDIRECTIONAL='TRUE';
      INPUT_LOAD='(-0.01,0.01)';
      OUTPUT_LOAD='(1.0,-1.0)';
    'IOC5':
      PIN_NUMBER='(C5)';
      BIDIRECTIONAL='TRUE';
      INPUT_LOAD='(-0.01,0.01)';
      OUTPUT_LOAD='(1.0,-1.0)';
    'IOC6':
      PIN_NUMBER='(C6)';
      BIDIRECTIONAL='TRUE';
      INPUT_LOAD='(-0.01,0.01)';
      OUTPUT_LOAD='(1.0,-1.0)';
    'IOC7':
      PIN_NUMBER='(C7)';
      BIDIRECTIONAL='TRUE';
      INPUT_LOAD='(-0.01,0.01)';
      OUTPUT_LOAD='(1.0,-1.0)';
    'IOC8':
      PIN_NUMBER='(C8)';
      BIDIRECTIONAL='TRUE';
      INPUT_LOAD='(-0.01,0.01)';
      OUTPUT_LOAD='(1.0,-1.0)';
    'IOC9':
      PIN_NUMBER='(C9)';
      BIDIRECTIONAL='TRUE';
      INPUT_LOAD='(-0.01,0.01)';
      OUTPUT_LOAD='(1.0,-1.0)';
    'IOD1':
      PIN_NUMBER='(D1)';
      BIDIRECTIONAL='TRUE';
      INPUT_LOAD='(-0.01,0.01)';
      OUTPUT_LOAD='(1.0,-1.0)';
    'IOD10':
      PIN_NUMBER='(D10)';
      BIDIRECTIONAL='TRUE';
      INPUT_LOAD='(-0.01,0.01)';
      OUTPUT_LOAD='(1.0,-1.0)';
    'IOD11':
      PIN_NUMBER='(D11)';
      BIDIRECTIONAL='TRUE';
      INPUT_LOAD='(-0.01,0.01)';
      OUTPUT_LOAD='(1.0,-1.0)';
    'IOD12':
      PIN_NUMBER='(D12)';
      BIDIRECTIONAL='TRUE';
      INPUT_LOAD='(-0.01,0.01)';
      OUTPUT_LOAD='(1.0,-1.0)';
    'IOD13':
      PIN_NUMBER='(D13)';
      BIDIRECTIONAL='TRUE';
      INPUT_LOAD='(-0.01,0.01)';
      OUTPUT_LOAD='(1.0,-1.0)';
    'IOD14':
      PIN_NUMBER='(D14)';
      BIDIRECTIONAL='TRUE';
      INPUT_LOAD='(-0.01,0.01)';
      OUTPUT_LOAD='(1.0,-1.0)';
    'IOD15':
      PIN_NUMBER='(D15)';
      BIDIRECTIONAL='TRUE';
      INPUT_LOAD='(-0.01,0.01)';
      OUTPUT_LOAD='(1.0,-1.0)';
    'IOD16':
      PIN_NUMBER='(D16)';
      BIDIRECTIONAL='TRUE';
      INPUT_LOAD='(-0.01,0.01)';
      OUTPUT_LOAD='(1.0,-1.0)';
    'IOD17':
      PIN_NUMBER='(D17)';
      BIDIRECTIONAL='TRUE';
      INPUT_LOAD='(-0.01,0.01)';
      OUTPUT_LOAD='(1.0,-1.0)';
    'IOD18':
      PIN_NUMBER='(D18)';
      BIDIRECTIONAL='TRUE';
      INPUT_LOAD='(-0.01,0.01)';
      OUTPUT_LOAD='(1.0,-1.0)';
    'IOD19':
      PIN_NUMBER='(D19)';
      BIDIRECTIONAL='TRUE';
      INPUT_LOAD='(-0.01,0.01)';
      OUTPUT_LOAD='(1.0,-1.0)';
    'IOD2':
      PIN_NUMBER='(D2)';
      BIDIRECTIONAL='TRUE';
      INPUT_LOAD='(-0.01,0.01)';
      OUTPUT_LOAD='(1.0,-1.0)';
    'IOD20':
      PIN_NUMBER='(D20)';
      BIDIRECTIONAL='TRUE';
      INPUT_LOAD='(-0.01,0.01)';
      OUTPUT_LOAD='(1.0,-1.0)';
    'IOD3':
      PIN_NUMBER='(D3)';
      BIDIRECTIONAL='TRUE';
      INPUT_LOAD='(-0.01,0.01)';
      OUTPUT_LOAD='(1.0,-1.0)';
    'IOD4':
      PIN_NUMBER='(D4)';
      BIDIRECTIONAL='TRUE';
      INPUT_LOAD='(-0.01,0.01)';
      OUTPUT_LOAD='(1.0,-1.0)';
    'IOD5':
      PIN_NUMBER='(D5)';
      BIDIRECTIONAL='TRUE';
      INPUT_LOAD='(-0.01,0.01)';
      OUTPUT_LOAD='(1.0,-1.0)';
    'IOD6':
      PIN_NUMBER='(D6)';
      BIDIRECTIONAL='TRUE';
      INPUT_LOAD='(-0.01,0.01)';
      OUTPUT_LOAD='(1.0,-1.0)';
    'IOD7':
      PIN_NUMBER='(D7)';
      BIDIRECTIONAL='TRUE';
      INPUT_LOAD='(-0.01,0.01)';
      OUTPUT_LOAD='(1.0,-1.0)';
    'IOD8':
      PIN_NUMBER='(D8)';
      BIDIRECTIONAL='TRUE';
      INPUT_LOAD='(-0.01,0.01)';
      OUTPUT_LOAD='(1.0,-1.0)';
    'IOD9':
      PIN_NUMBER='(D9)';
      BIDIRECTIONAL='TRUE';
      INPUT_LOAD='(-0.01,0.01)';
      OUTPUT_LOAD='(1.0,-1.0)';
    'IOE1':
      PIN_NUMBER='(E1)';
      BIDIRECTIONAL='TRUE';
      INPUT_LOAD='(-0.01,0.01)';
      OUTPUT_LOAD='(1.0,-1.0)';
    'IOE10':
      PIN_NUMBER='(E10)';
      BIDIRECTIONAL='TRUE';
      INPUT_LOAD='(-0.01,0.01)';
      OUTPUT_LOAD='(1.0,-1.0)';
    'IOE11':
      PIN_NUMBER='(E11)';
      BIDIRECTIONAL='TRUE';
      INPUT_LOAD='(-0.01,0.01)';
      OUTPUT_LOAD='(1.0,-1.0)';
    'IOE12':
      PIN_NUMBER='(E12)';
      BIDIRECTIONAL='TRUE';
      INPUT_LOAD='(-0.01,0.01)';
      OUTPUT_LOAD='(1.0,-1.0)';
    'IOE13':
      PIN_NUMBER='(E13)';
      BIDIRECTIONAL='TRUE';
      INPUT_LOAD='(-0.01,0.01)';
      OUTPUT_LOAD='(1.0,-1.0)';
    'IOE14':
      PIN_NUMBER='(E14)';
      BIDIRECTIONAL='TRUE';
      INPUT_LOAD='(-0.01,0.01)';
      OUTPUT_LOAD='(1.0,-1.0)';
    'IOE15':
      PIN_NUMBER='(E15)';
      BIDIRECTIONAL='TRUE';
      INPUT_LOAD='(-0.01,0.01)';
      OUTPUT_LOAD='(1.0,-1.0)';
    'IOE16':
      PIN_NUMBER='(E16)';
      BIDIRECTIONAL='TRUE';
      INPUT_LOAD='(-0.01,0.01)';
      OUTPUT_LOAD='(1.0,-1.0)';
    'IOE17':
      PIN_NUMBER='(E17)';
      BIDIRECTIONAL='TRUE';
      INPUT_LOAD='(-0.01,0.01)';
      OUTPUT_LOAD='(1.0,-1.0)';
    'IOE18':
      PIN_NUMBER='(E18)';
      BIDIRECTIONAL='TRUE';
      INPUT_LOAD='(-0.01,0.01)';
      OUTPUT_LOAD='(1.0,-1.0)';
    'IOE19':
      PIN_NUMBER='(E19)';
      BIDIRECTIONAL='TRUE';
      INPUT_LOAD='(-0.01,0.01)';
      OUTPUT_LOAD='(1.0,-1.0)';
    'IOE2':
      PIN_NUMBER='(E2)';
      BIDIRECTIONAL='TRUE';
      INPUT_LOAD='(-0.01,0.01)';
      OUTPUT_LOAD='(1.0,-1.0)';
    'IOE20':
      PIN_NUMBER='(E20)';
      BIDIRECTIONAL='TRUE';
      INPUT_LOAD='(-0.01,0.01)';
      OUTPUT_LOAD='(1.0,-1.0)';
    'IOE3':
      PIN_NUMBER='(E3)';
      BIDIRECTIONAL='TRUE';
      INPUT_LOAD='(-0.01,0.01)';
      OUTPUT_LOAD='(1.0,-1.0)';
    'IOE4':
      PIN_NUMBER='(E4)';
      BIDIRECTIONAL='TRUE';
      INPUT_LOAD='(-0.01,0.01)';
      OUTPUT_LOAD='(1.0,-1.0)';
    'IOE5':
      PIN_NUMBER='(E5)';
      BIDIRECTIONAL='TRUE';
      INPUT_LOAD='(-0.01,0.01)';
      OUTPUT_LOAD='(1.0,-1.0)';
    'IOE6':
      PIN_NUMBER='(E6)';
      BIDIRECTIONAL='TRUE';
      INPUT_LOAD='(-0.01,0.01)';
      OUTPUT_LOAD='(1.0,-1.0)';
    'IOE7':
      PIN_NUMBER='(E7)';
      BIDIRECTIONAL='TRUE';
      INPUT_LOAD='(-0.01,0.01)';
      OUTPUT_LOAD='(1.0,-1.0)';
    'IOE8':
      PIN_NUMBER='(E8)';
      BIDIRECTIONAL='TRUE';
      INPUT_LOAD='(-0.01,0.01)';
      OUTPUT_LOAD='(1.0,-1.0)';
    'IOE9':
      PIN_NUMBER='(E9)';
      BIDIRECTIONAL='TRUE';
      INPUT_LOAD='(-0.01,0.01)';
      OUTPUT_LOAD='(1.0,-1.0)';
    'IOF1':
      PIN_NUMBER='(F1)';
      BIDIRECTIONAL='TRUE';
      INPUT_LOAD='(-0.01,0.01)';
      OUTPUT_LOAD='(1.0,-1.0)';
    'IOF10':
      PIN_NUMBER='(F10)';
      BIDIRECTIONAL='TRUE';
      INPUT_LOAD='(-0.01,0.01)';
      OUTPUT_LOAD='(1.0,-1.0)';
    'IOF11':
      PIN_NUMBER='(F11)';
      BIDIRECTIONAL='TRUE';
      INPUT_LOAD='(-0.01,0.01)';
      OUTPUT_LOAD='(1.0,-1.0)';
    'IOF12':
      PIN_NUMBER='(F12)';
      BIDIRECTIONAL='TRUE';
      INPUT_LOAD='(-0.01,0.01)';
      OUTPUT_LOAD='(1.0,-1.0)';
    'IOF13':
      PIN_NUMBER='(F13)';
      BIDIRECTIONAL='TRUE';
      INPUT_LOAD='(-0.01,0.01)';
      OUTPUT_LOAD='(1.0,-1.0)';
    'IOF14':
      PIN_NUMBER='(F14)';
      BIDIRECTIONAL='TRUE';
      INPUT_LOAD='(-0.01,0.01)';
      OUTPUT_LOAD='(1.0,-1.0)';
    'IOF15':
      PIN_NUMBER='(F15)';
      BIDIRECTIONAL='TRUE';
      INPUT_LOAD='(-0.01,0.01)';
      OUTPUT_LOAD='(1.0,-1.0)';
    'IOF16':
      PIN_NUMBER='(F16)';
      BIDIRECTIONAL='TRUE';
      INPUT_LOAD='(-0.01,0.01)';
      OUTPUT_LOAD='(1.0,-1.0)';
    'IOF17':
      PIN_NUMBER='(F17)';
      BIDIRECTIONAL='TRUE';
      INPUT_LOAD='(-0.01,0.01)';
      OUTPUT_LOAD='(1.0,-1.0)';
    'IOF18':
      PIN_NUMBER='(F18)';
      BIDIRECTIONAL='TRUE';
      INPUT_LOAD='(-0.01,0.01)';
      OUTPUT_LOAD='(1.0,-1.0)';
    'IOF19':
      PIN_NUMBER='(F19)';
      BIDIRECTIONAL='TRUE';
      INPUT_LOAD='(-0.01,0.01)';
      OUTPUT_LOAD='(1.0,-1.0)';
    'IOF2':
      PIN_NUMBER='(F2)';
      BIDIRECTIONAL='TRUE';
      INPUT_LOAD='(-0.01,0.01)';
      OUTPUT_LOAD='(1.0,-1.0)';
    'IOF20':
      PIN_NUMBER='(F20)';
      BIDIRECTIONAL='TRUE';
      INPUT_LOAD='(-0.01,0.01)';
      OUTPUT_LOAD='(1.0,-1.0)';
    'IOF3':
      PIN_NUMBER='(F3)';
      BIDIRECTIONAL='TRUE';
      INPUT_LOAD='(-0.01,0.01)';
      OUTPUT_LOAD='(1.0,-1.0)';
    'IOF4':
      PIN_NUMBER='(F4)';
      BIDIRECTIONAL='TRUE';
      INPUT_LOAD='(-0.01,0.01)';
      OUTPUT_LOAD='(1.0,-1.0)';
    'IOF5':
      PIN_NUMBER='(F5)';
      BIDIRECTIONAL='TRUE';
      INPUT_LOAD='(-0.01,0.01)';
      OUTPUT_LOAD='(1.0,-1.0)';
    'IOF6':
      PIN_NUMBER='(F6)';
      BIDIRECTIONAL='TRUE';
      INPUT_LOAD='(-0.01,0.01)';
      OUTPUT_LOAD='(1.0,-1.0)';
    'IOF7':
      PIN_NUMBER='(F7)';
      BIDIRECTIONAL='TRUE';
      INPUT_LOAD='(-0.01,0.01)';
      OUTPUT_LOAD='(1.0,-1.0)';
    'IOF8':
      PIN_NUMBER='(F8)';
      BIDIRECTIONAL='TRUE';
      INPUT_LOAD='(-0.01,0.01)';
      OUTPUT_LOAD='(1.0,-1.0)';
    'IOF9':
      PIN_NUMBER='(F9)';
      BIDIRECTIONAL='TRUE';
      INPUT_LOAD='(-0.01,0.01)';
      OUTPUT_LOAD='(1.0,-1.0)';
  end_pin;
  body
    PART_NAME='SCONN120_H61426002';
    PHYS_DES_PREFIX='J';
  end_body;
end_primitive;

END.
